(kicad_pcb
	(version 20260206)
	(generator "pcbnew")
	(generator_version "10.0")
	(general
		(thickness 1.6)
		(legacy_teardrops no)
	)
	(paper "A4")
	(title_block
		(title "panther-plus-userver — 13130-1b_20150205.brd")
		(comment 1 "Honey Badger (Wiwynn) / footprint 406 of 1509 (DIMM2), pads 44-50 of 210")
	)
	(layers
		(0 "F.Cu" signal "TOP")
		(4 "In1.Cu" signal "L2")
		(6 "In2.Cu" signal "L3")
		(8 "In3.Cu" signal "L4")
		(10 "In4.Cu" signal "L5")
		(12 "In5.Cu" signal "L6")
		(14 "In6.Cu" signal "L7")
		(16 "In7.Cu" signal "L8")
		(18 "In8.Cu" signal "L9")
		(20 "In9.Cu" signal "L10")
		(22 "In10.Cu" signal "L11")
		(2 "B.Cu" signal "BOTTOM")
		(9 "F.Adhes" user "F.Adhesive")
		(11 "B.Adhes" user "B.Adhesive")
		(13 "F.Paste" user "Package Geometry/Pastemask Top")
		(15 "B.Paste" user "Package Geometry/Pastemask Bottom")
		(5 "F.SilkS" user "Ref Des/Silkscreen Top")
		(7 "B.SilkS" user "Ref Des/Silkscreen Bottom")
		(1 "F.Mask" user "Board Geometry/Soldermask Top")
		(3 "B.Mask" user "Board Geometry/Soldermask Bottom")
		(17 "Dwgs.User" user "User.Drawings")
		(19 "Cmts.User" user "User.Comments")
		(21 "Eco1.User" user "User.Eco1")
		(23 "Eco2.User" user "User.Eco2")
		(25 "Edge.Cuts" user "Board Geometry/Outline")
		(27 "Margin" user)
		(31 "F.CrtYd" user "Package Geometry/Place Bound Top")
		(29 "B.CrtYd" user "Package Geometry/Place Bound Bottom")
		(35 "F.Fab" user "Ref Des/Assembly Top")
		(33 "B.Fab" user "Ref Des/Assembly Bottom")
	)
	(footprint ""
		(layer "F.Cu")
		(at 158.500064 -66.699892 180)
		(property "Reference" "DIMM2"
			(at 0 0 180)
			(layer "F.SilkS")
			(hide yes)
			(effects
				(font
					(size 1.27 1.27)
				)
			)
		)
		(property "Value" "DDR3-204P-174-COLAY-1-GP"
			(at -40.682164 -17.468088 180)
			(unlocked yes)
			(layer "F.Fab")
			(hide yes)
			(effects
				(font
					(size 1.016 1.016)
					(thickness 0.1524)
				)
			)
		)
		(property "Device Type" "AS0A626-H8SN-7H-COLAY-1"
			(at -40.682164 -18.992088 180)
			(unlocked yes)
			(layer "F.Fab")
			(hide yes)
			(effects
				(font
					(size 1.016 1.016)
					(thickness 0.1524)
				)
			)
		)
		(duplicate_pad_numbers_are_jumpers no)
		(pad "42" smd custom
			(at -19.349974 -4.106672 180)
			(size 0.1143 0.1143)
			(layers "F.Cu" "F.Mask" "F.Paste")
			(net "M_A_DQ17")
			(options
				(clearance outline)
				(anchor circle)
			)
			(primitives
				(gr_poly
					(pts
						(xy 0 0.9017) (xy -0.03175 0.89916) (xy -0.0635 0.889) (xy -0.09144 0.87376) (xy -0.11684 0.85344)
						(xy -0.13716 0.82804) (xy -0.1524 0.8001) (xy -0.16256 0.76835) (xy -0.1651 0.7366) (xy -0.1651 0.44958)
						(xy -0.17272 0.44196) (xy -0.19812 0.4064) (xy -0.2032 0.39624) (xy -0.20701 0.38735) (xy -0.21209 0.37719)
						(xy -0.2159 0.36703) (xy -0.21844 0.35687) (xy -0.22225 0.34544) (xy -0.22352 0.33528) (xy -0.22606 0.32512)
						(xy -0.22733 0.31369) (xy -0.22733 0.30353) (xy -0.2286 0.2921) (xy -0.22733 0.28067) (xy -0.22733 0.27051)
						(xy -0.22606 0.25908) (xy -0.22352 0.24892) (xy -0.22225 0.23876) (xy -0.21844 0.22733) (xy -0.2159 0.21717)
						(xy -0.21209 0.20701) (xy -0.20701 0.19685) (xy -0.2032 0.18796) (xy -0.19812 0.1778) (xy -0.17272 0.14224)
						(xy -0.1651 0.13462) (xy -0.1651 -0.7366) (xy -0.16256 -0.76835) (xy -0.1524 -0.8001) (xy -0.13716 -0.82804)
						(xy -0.11684 -0.85344) (xy -0.09144 -0.87376) (xy -0.0635 -0.889) (xy -0.03175 -0.89916) (xy 0 -0.9017)
						(xy 0.03175 -0.89916) (xy 0.0635 -0.889) (xy 0.09144 -0.87376) (xy 0.11684 -0.85344) (xy 0.13716 -0.82804)
						(xy 0.1524 -0.8001) (xy 0.16256 -0.76835) (xy 0.1651 -0.7366) (xy 0.1651 0.13462) (xy 0.17272 0.14224)
						(xy 0.19812 0.1778) (xy 0.2032 0.18796) (xy 0.20701 0.19685) (xy 0.21209 0.20701) (xy 0.2159 0.21717)
						(xy 0.21844 0.22733) (xy 0.22225 0.23876) (xy 0.22352 0.24892) (xy 0.22606 0.25908) (xy 0.22733 0.27051)
						(xy 0.22733 0.28067) (xy 0.2286 0.2921) (xy 0.22733 0.30353) (xy 0.22733 0.31369) (xy 0.22606 0.32512)
						(xy 0.22352 0.33528) (xy 0.22225 0.34544) (xy 0.21844 0.35687) (xy 0.2159 0.36703) (xy 0.21209 0.37719)
						(xy 0.20701 0.38735) (xy 0.2032 0.39624) (xy 0.19812 0.4064) (xy 0.17272 0.44196) (xy 0.1651 0.44958)
						(xy 0.1651 0.7366) (xy 0.16256 0.76835) (xy 0.1524 0.8001) (xy 0.13716 0.82804) (xy 0.11684 0.85344)
						(xy 0.09144 0.87376) (xy 0.0635 0.889) (xy 0.03175 0.89916)
					)
					(width 0)
					(fill yes)
				)
			)
		)
		(pad "43" smd custom
			(at -19.05 4.106672 180)
			(size 0.1143 0.1143)
			(layers "F.Cu" "F.Mask" "F.Paste")
			(net "M_A_DQS_DN2")
			(options
				(clearance outline)
				(anchor circle)
			)
			(primitives
				(gr_poly
					(pts
						(xy 0 0.9017) (xy -0.03175 0.89916) (xy -0.0635 0.889) (xy -0.09144 0.87376) (xy -0.11684 0.85344)
						(xy -0.13716 0.82804) (xy -0.1524 0.8001) (xy -0.16256 0.76835) (xy -0.1651 0.7366) (xy -0.1651 0.11938)
						(xy -0.17272 0.11176) (xy -0.19812 0.0762) (xy -0.2032 0.06604) (xy -0.20701 0.05715) (xy -0.21209 0.04699)
						(xy -0.2159 0.03683) (xy -0.21844 0.02667) (xy -0.22225 0.01524) (xy -0.22352 0.00508) (xy -0.22606 -0.00508)
						(xy -0.22733 -0.01651) (xy -0.22733 -0.02667) (xy -0.2286 -0.0381) (xy -0.22733 -0.04953) (xy -0.22733 -0.05969)
						(xy -0.22606 -0.07112) (xy -0.22352 -0.08128) (xy -0.22225 -0.09144) (xy -0.21844 -0.10287) (xy -0.2159 -0.11303)
						(xy -0.21209 -0.12319) (xy -0.20701 -0.13335) (xy -0.2032 -0.14224) (xy -0.19812 -0.1524) (xy -0.17272 -0.18796)
						(xy -0.1651 -0.19558) (xy -0.1651 -0.7366) (xy -0.16256 -0.76835) (xy -0.1524 -0.8001) (xy -0.13716 -0.82804)
						(xy -0.11684 -0.85344) (xy -0.09144 -0.87376) (xy -0.0635 -0.889) (xy -0.03175 -0.89916) (xy 0 -0.9017)
						(xy 0.03175 -0.89916) (xy 0.0635 -0.889) (xy 0.09144 -0.87376) (xy 0.11684 -0.85344) (xy 0.13716 -0.82804)
						(xy 0.1524 -0.8001) (xy 0.16256 -0.76835) (xy 0.1651 -0.7366) (xy 0.1651 -0.19685) (xy 0.17272 -0.18923)
						(xy 0.17907 -0.18034) (xy 0.18669 -0.17145) (xy 0.19177 -0.16256) (xy 0.19812 -0.15367) (xy 0.20828 -0.13335)
						(xy 0.21971 -0.10287) (xy 0.22225 -0.09271) (xy 0.22479 -0.08128) (xy 0.22606 -0.07112) (xy 0.2286 -0.05969)
						(xy 0.2286 -0.01651) (xy 0.22606 -0.00508) (xy 0.22479 0.00508) (xy 0.22225 0.01651) (xy 0.21971 0.02667)
						(xy 0.20828 0.05715) (xy 0.19812 0.07747) (xy 0.19177 0.08636) (xy 0.18669 0.09525) (xy 0.17907 0.10414)
						(xy 0.17272 0.11303) (xy 0.1651 0.12065) (xy 0.1651 0.7366) (xy 0.16256 0.76835) (xy 0.1524 0.8001)
						(xy 0.13716 0.82804) (xy 0.11684 0.85344) (xy 0.09144 0.87376) (xy 0.0635 0.889) (xy 0.03175 0.89916)
					)
					(width 0)
					(fill yes)
				)
			)
		)
		(pad "44" smd custom
			(at -18.750026 -4.106672 180)
			(size 0.1143 0.1143)
			(layers "F.Cu" "F.Mask" "F.Paste")
			(net "GND")
			(options
				(clearance outline)
				(anchor circle)
			)
			(primitives
				(gr_poly
					(pts
						(xy 0 0.9017) (xy -0.03175 0.89916) (xy -0.0635 0.889) (xy -0.09144 0.87376) (xy -0.11684 0.85344)
						(xy -0.13716 0.82804) (xy -0.1524 0.8001) (xy -0.16256 0.76835) (xy -0.1651 0.7366) (xy -0.1651 0.19685)
						(xy -0.17272 0.18923) (xy -0.17907 0.18034) (xy -0.18669 0.17145) (xy -0.19177 0.16256) (xy -0.19812 0.15367)
						(xy -0.20828 0.13335) (xy -0.21971 0.10287) (xy -0.22225 0.09271) (xy -0.22479 0.08128) (xy -0.22606 0.07112)
						(xy -0.2286 0.05969) (xy -0.2286 0.01651) (xy -0.22606 0.00508) (xy -0.22479 -0.00508) (xy -0.22225 -0.01651)
						(xy -0.21971 -0.02667) (xy -0.20828 -0.05715) (xy -0.19812 -0.07747) (xy -0.19177 -0.08636) (xy -0.18669 -0.09525)
						(xy -0.17907 -0.10414) (xy -0.17272 -0.11303) (xy -0.1651 -0.12065) (xy -0.1651 -0.7366) (xy -0.16256 -0.76835)
						(xy -0.1524 -0.8001) (xy -0.13716 -0.82804) (xy -0.11684 -0.85344) (xy -0.09144 -0.87376) (xy -0.0635 -0.889)
						(xy -0.03175 -0.89916) (xy 0 -0.9017) (xy 0.03175 -0.89916) (xy 0.0635 -0.889) (xy 0.09144 -0.87376)
						(xy 0.11684 -0.85344) (xy 0.13716 -0.82804) (xy 0.1524 -0.8001) (xy 0.16256 -0.76835) (xy 0.1651 -0.7366)
						(xy 0.1651 -0.11938) (xy 0.17272 -0.11176) (xy 0.19812 -0.0762) (xy 0.2032 -0.06604) (xy 0.20701 -0.05715)
						(xy 0.21209 -0.04699) (xy 0.2159 -0.03683) (xy 0.21844 -0.02667) (xy 0.22225 -0.01524) (xy 0.22352 -0.00508)
						(xy 0.22606 0.00508) (xy 0.22733 0.01651) (xy 0.22733 0.02667) (xy 0.2286 0.0381) (xy 0.22733 0.04953)
						(xy 0.22733 0.05969) (xy 0.22606 0.07112) (xy 0.22352 0.08128) (xy 0.22225 0.09144) (xy 0.21844 0.10287)
						(xy 0.2159 0.11303) (xy 0.21209 0.12319) (xy 0.20701 0.13335) (xy 0.2032 0.14224) (xy 0.19812 0.1524)
						(xy 0.17272 0.18796) (xy 0.1651 0.19558) (xy 0.1651 0.7366) (xy 0.16256 0.76835) (xy 0.1524 0.8001)
						(xy 0.13716 0.82804) (xy 0.11684 0.85344) (xy 0.09144 0.87376) (xy 0.0635 0.889) (xy 0.03175 0.89916)
					)
					(width 0)
					(fill yes)
				)
			)
		)
		(pad "45" smd custom
			(at -18.450052 4.106672 180)
			(size 0.1143 0.1143)
			(layers "F.Cu" "F.Mask" "F.Paste")
			(net "M_A_DQS_DP2")
			(options
				(clearance outline)
				(anchor circle)
			)
			(primitives
				(gr_poly
					(pts
						(xy 0 0.9017) (xy -0.03175 0.89916) (xy -0.0635 0.889) (xy -0.09144 0.87376) (xy -0.11684 0.85344)
						(xy -0.13716 0.82804) (xy -0.1524 0.8001) (xy -0.16256 0.76835) (xy -0.1651 0.7366) (xy -0.1651 -0.13462)
						(xy -0.17272 -0.14224) (xy -0.19812 -0.1778) (xy -0.2032 -0.18796) (xy -0.20701 -0.19685) (xy -0.21209 -0.20701)
						(xy -0.2159 -0.21717) (xy -0.21844 -0.22733) (xy -0.22225 -0.23876) (xy -0.22352 -0.24892) (xy -0.22606 -0.25908)
						(xy -0.22733 -0.27051) (xy -0.22733 -0.28067) (xy -0.2286 -0.2921) (xy -0.22733 -0.30353) (xy -0.22733 -0.31369)
						(xy -0.22606 -0.32512) (xy -0.22352 -0.33528) (xy -0.22225 -0.34544) (xy -0.21844 -0.35687) (xy -0.2159 -0.36703)
						(xy -0.21209 -0.37719) (xy -0.20701 -0.38735) (xy -0.2032 -0.39624) (xy -0.19812 -0.4064) (xy -0.17272 -0.44196)
						(xy -0.1651 -0.44958) (xy -0.1651 -0.7366) (xy -0.16256 -0.76835) (xy -0.1524 -0.8001) (xy -0.13716 -0.82804)
						(xy -0.11684 -0.85344) (xy -0.09144 -0.87376) (xy -0.0635 -0.889) (xy -0.03175 -0.89916) (xy 0 -0.9017)
						(xy 0.03175 -0.89916) (xy 0.0635 -0.889) (xy 0.09144 -0.87376) (xy 0.11684 -0.85344) (xy 0.13716 -0.82804)
						(xy 0.1524 -0.8001) (xy 0.16256 -0.76835) (xy 0.1651 -0.7366) (xy 0.1651 -0.44958) (xy 0.17272 -0.44196)
						(xy 0.19812 -0.4064) (xy 0.2032 -0.39624) (xy 0.20701 -0.38735) (xy 0.21209 -0.37719) (xy 0.2159 -0.36703)
						(xy 0.21844 -0.35687) (xy 0.22225 -0.34544) (xy 0.22352 -0.33528) (xy 0.22606 -0.32512) (xy 0.22733 -0.31369)
						(xy 0.22733 -0.30353) (xy 0.2286 -0.2921) (xy 0.22733 -0.28067) (xy 0.22733 -0.27051) (xy 0.22606 -0.25908)
						(xy 0.22352 -0.24892) (xy 0.22225 -0.23876) (xy 0.21844 -0.22733) (xy 0.2159 -0.21717) (xy 0.21209 -0.20701)
						(xy 0.20701 -0.19685) (xy 0.2032 -0.18796) (xy 0.19812 -0.1778) (xy 0.17272 -0.14224) (xy 0.1651 -0.13462)
						(xy 0.1651 0.7366) (xy 0.16256 0.76835) (xy 0.1524 0.8001) (xy 0.13716 0.82804) (xy 0.11684 0.85344)
						(xy 0.09144 0.87376) (xy 0.0635 0.889) (xy 0.03175 0.89916)
					)
					(width 0)
					(fill yes)
				)
			)
		)
		(pad "46" smd custom
			(at -18.150078 -4.106672 180)
			(size 0.1143 0.1143)
			(layers "F.Cu" "F.Mask" "F.Paste")
			(net "GND")
			(options
				(clearance outline)
				(anchor circle)
			)
			(primitives
				(gr_poly
					(pts
						(xy 0 0.9017) (xy -0.03175 0.89916) (xy -0.0635 0.889) (xy -0.09144 0.87376) (xy -0.11684 0.85344)
						(xy -0.13716 0.82804) (xy -0.1524 0.8001) (xy -0.16256 0.76835) (xy -0.1651 0.7366) (xy -0.1651 0.44958)
						(xy -0.17272 0.44196) (xy -0.19812 0.4064) (xy -0.2032 0.39624) (xy -0.20701 0.38735) (xy -0.21209 0.37719)
						(xy -0.2159 0.36703) (xy -0.21844 0.35687) (xy -0.22225 0.34544) (xy -0.22352 0.33528) (xy -0.22606 0.32512)
						(xy -0.22733 0.31369) (xy -0.22733 0.30353) (xy -0.2286 0.2921) (xy -0.22733 0.28067) (xy -0.22733 0.27051)
						(xy -0.22606 0.25908) (xy -0.22352 0.24892) (xy -0.22225 0.23876) (xy -0.21844 0.22733) (xy -0.2159 0.21717)
						(xy -0.21209 0.20701) (xy -0.20701 0.19685) (xy -0.2032 0.18796) (xy -0.19812 0.1778) (xy -0.17272 0.14224)
						(xy -0.1651 0.13462) (xy -0.1651 -0.7366) (xy -0.16256 -0.76835) (xy -0.1524 -0.8001) (xy -0.13716 -0.82804)
						(xy -0.11684 -0.85344) (xy -0.09144 -0.87376) (xy -0.0635 -0.889) (xy -0.03175 -0.89916) (xy 0 -0.9017)
						(xy 0.03175 -0.89916) (xy 0.0635 -0.889) (xy 0.09144 -0.87376) (xy 0.11684 -0.85344) (xy 0.13716 -0.82804)
						(xy 0.1524 -0.8001) (xy 0.16256 -0.76835) (xy 0.1651 -0.7366) (xy 0.1651 0.13462) (xy 0.17272 0.14224)
						(xy 0.19812 0.1778) (xy 0.2032 0.18796) (xy 0.20701 0.19685) (xy 0.21209 0.20701) (xy 0.2159 0.21717)
						(xy 0.21844 0.22733) (xy 0.22225 0.23876) (xy 0.22352 0.24892) (xy 0.22606 0.25908) (xy 0.22733 0.27051)
						(xy 0.22733 0.28067) (xy 0.2286 0.2921) (xy 0.22733 0.30353) (xy 0.22733 0.31369) (xy 0.22606 0.32512)
						(xy 0.22352 0.33528) (xy 0.22225 0.34544) (xy 0.21844 0.35687) (xy 0.2159 0.36703) (xy 0.21209 0.37719)
						(xy 0.20701 0.38735) (xy 0.2032 0.39624) (xy 0.19812 0.4064) (xy 0.17272 0.44196) (xy 0.1651 0.44958)
						(xy 0.1651 0.7366) (xy 0.16256 0.76835) (xy 0.1524 0.8001) (xy 0.13716 0.82804) (xy 0.11684 0.85344)
						(xy 0.09144 0.87376) (xy 0.0635 0.889) (xy 0.03175 0.89916)
					)
					(width 0)
					(fill yes)
				)
			)
		)
		(pad "47" smd custom
			(at -17.850104 4.106672 180)
			(size 0.1143 0.1143)
			(layers "F.Cu" "F.Mask" "F.Paste")
			(net "GND")
			(options
				(clearance outline)
				(anchor circle)
			)
			(primitives
				(gr_poly
					(pts
						(xy 0 0.9017) (xy -0.03175 0.89916) (xy -0.0635 0.889) (xy -0.09144 0.87376) (xy -0.11684 0.85344)
						(xy -0.13716 0.82804) (xy -0.1524 0.8001) (xy -0.16256 0.76835) (xy -0.1651 0.7366) (xy -0.1651 0.11938)
						(xy -0.17272 0.11176) (xy -0.19812 0.0762) (xy -0.2032 0.06604) (xy -0.20701 0.05715) (xy -0.21209 0.04699)
						(xy -0.2159 0.03683) (xy -0.21844 0.02667) (xy -0.22225 0.01524) (xy -0.22352 0.00508) (xy -0.22606 -0.00508)
						(xy -0.22733 -0.01651) (xy -0.22733 -0.02667) (xy -0.2286 -0.0381) (xy -0.22733 -0.04953) (xy -0.22733 -0.05969)
						(xy -0.22606 -0.07112) (xy -0.22352 -0.08128) (xy -0.22225 -0.09144) (xy -0.21844 -0.10287) (xy -0.2159 -0.11303)
						(xy -0.21209 -0.12319) (xy -0.20701 -0.13335) (xy -0.2032 -0.14224) (xy -0.19812 -0.1524) (xy -0.17272 -0.18796)
						(xy -0.1651 -0.19558) (xy -0.1651 -0.7366) (xy -0.16256 -0.76835) (xy -0.1524 -0.8001) (xy -0.13716 -0.82804)
						(xy -0.11684 -0.85344) (xy -0.09144 -0.87376) (xy -0.0635 -0.889) (xy -0.03175 -0.89916) (xy 0 -0.9017)
						(xy 0.03175 -0.89916) (xy 0.0635 -0.889) (xy 0.09144 -0.87376) (xy 0.11684 -0.85344) (xy 0.13716 -0.82804)
						(xy 0.1524 -0.8001) (xy 0.16256 -0.76835) (xy 0.1651 -0.7366) (xy 0.1651 -0.19685) (xy 0.17272 -0.18923)
						(xy 0.17907 -0.18034) (xy 0.18669 -0.17145) (xy 0.19177 -0.16256) (xy 0.19812 -0.15367) (xy 0.20828 -0.13335)
						(xy 0.21971 -0.10287) (xy 0.22225 -0.09271) (xy 0.22479 -0.08128) (xy 0.22606 -0.07112) (xy 0.2286 -0.05969)
						(xy 0.2286 -0.01651) (xy 0.22606 -0.00508) (xy 0.22479 0.00508) (xy 0.22225 0.01651) (xy 0.21971 0.02667)
						(xy 0.20828 0.05715) (xy 0.19812 0.07747) (xy 0.19177 0.08636) (xy 0.18669 0.09525) (xy 0.17907 0.10414)
						(xy 0.17272 0.11303) (xy 0.1651 0.12065) (xy 0.1651 0.7366) (xy 0.16256 0.76835) (xy 0.1524 0.8001)
						(xy 0.13716 0.82804) (xy 0.11684 0.85344) (xy 0.09144 0.87376) (xy 0.0635 0.889) (xy 0.03175 0.89916)
					)
					(width 0)
					(fill yes)
				)
			)
		)
		(pad "48" smd custom
			(at -17.549876 -4.106672 180)
			(size 0.1143 0.1143)
			(layers "F.Cu" "F.Mask" "F.Paste")
			(net "M_A_DQ18")
			(options
				(clearance outline)
				(anchor circle)
			)
			(primitives
				(gr_poly
					(pts
						(xy 0 0.9017) (xy -0.03175 0.89916) (xy -0.0635 0.889) (xy -0.09144 0.87376) (xy -0.11684 0.85344)
						(xy -0.13716 0.82804) (xy -0.1524 0.8001) (xy -0.16256 0.76835) (xy -0.1651 0.7366) (xy -0.1651 0.19685)
						(xy -0.17272 0.18923) (xy -0.17907 0.18034) (xy -0.18669 0.17145) (xy -0.19177 0.16256) (xy -0.19812 0.15367)
						(xy -0.20828 0.13335) (xy -0.21971 0.10287) (xy -0.22225 0.09271) (xy -0.22479 0.08128) (xy -0.22606 0.07112)
						(xy -0.2286 0.05969) (xy -0.2286 0.01651) (xy -0.22606 0.00508) (xy -0.22479 -0.00508) (xy -0.22225 -0.01651)
						(xy -0.21971 -0.02667) (xy -0.20828 -0.05715) (xy -0.19812 -0.07747) (xy -0.19177 -0.08636) (xy -0.18669 -0.09525)
						(xy -0.17907 -0.10414) (xy -0.17272 -0.11303) (xy -0.1651 -0.12065) (xy -0.1651 -0.7366) (xy -0.16256 -0.76835)
						(xy -0.1524 -0.8001) (xy -0.13716 -0.82804) (xy -0.11684 -0.85344) (xy -0.09144 -0.87376) (xy -0.0635 -0.889)
						(xy -0.03175 -0.89916) (xy 0 -0.9017) (xy 0.03175 -0.89916) (xy 0.0635 -0.889) (xy 0.09144 -0.87376)
						(xy 0.11684 -0.85344) (xy 0.13716 -0.82804) (xy 0.1524 -0.8001) (xy 0.16256 -0.76835) (xy 0.1651 -0.7366)
						(xy 0.1651 -0.11938) (xy 0.17272 -0.11176) (xy 0.19812 -0.0762) (xy 0.2032 -0.06604) (xy 0.20701 -0.05715)
						(xy 0.21209 -0.04699) (xy 0.2159 -0.03683) (xy 0.21844 -0.02667) (xy 0.22225 -0.01524) (xy 0.22352 -0.00508)
						(xy 0.22606 0.00508) (xy 0.22733 0.01651) (xy 0.22733 0.02667) (xy 0.2286 0.0381) (xy 0.22733 0.04953)
						(xy 0.22733 0.05969) (xy 0.22606 0.07112) (xy 0.22352 0.08128) (xy 0.22225 0.09144) (xy 0.21844 0.10287)
						(xy 0.2159 0.11303) (xy 0.21209 0.12319) (xy 0.20701 0.13335) (xy 0.2032 0.14224) (xy 0.19812 0.1524)
						(xy 0.17272 0.18796) (xy 0.1651 0.19558) (xy 0.1651 0.7366) (xy 0.16256 0.76835) (xy 0.1524 0.8001)
						(xy 0.13716 0.82804) (xy 0.11684 0.85344) (xy 0.09144 0.87376) (xy 0.0635 0.889) (xy 0.03175 0.89916)
					)
					(width 0)
					(fill yes)
				)
			)
		)
	)
)
